FILE_TYPE = MACRO_DRAWING;
SET COLOR_WIRE YELLOW;
SET COLOR_PROP ORANGE;
SET COLOR_DOT WHITE;
SET COLOR_ARC YELLOW;
SET COLOR_BODY GREEN;
SET COLOR_NOTE PURPLE;
SET PROP_DISPLAY VALUE;
SET PAGE_NUMBER P127;
FORCEADD QUANTA_TITLE_BLOCK_C..1
(0 0);
FORCEPROP 1 LAST CUSTOM_TXT_CDS <NAME_2>
J 0
(-3175 50);
FORCEPROP 1 LAST CUSTOM_TXT_CDS <NAME_1>
J 0
(-3175 175);
FORCEPROP 1 LAST CUSTOM_TXT_CDS <Q_NUMBER>
J 0
(-1403 103);
DISPLAY 1.212766 (-1403 103);
FORCEPROP 1 LAST CUSTOM_TXT_CDS <Q_PROJ>
J 0
(-2382 102);
DISPLAY 1.212766 (-2382 102);
FORCEPROP 1 LAST CUSTOM_TXT_CDS <Q_REV>
J 0
(-184 103);
DISPLAY 1.212766 (-184 103);
FORCEPROP 1 LAST CUSTOM_TXT_CDS <CON_LAST_MODIFIED>
J 0
(-1885 15);
DISPLAY 0.978723 (-1885 15);
FORCEPROP 1 LAST CUSTOM_TXT_CDS <CON_PAGE_NUM> OF <CON_TOTAL_PAGES>
J 0
(-446 18);
DISPLAY 0.978723 (-446 18);
FORCEPROP 1 LAST Q_TITLE E1.S CONN4
J 0
(-9366 26);
DISPLAY 2.446809 (-9366 26);
PAINT GREEN (-9366 26);
FORCEPROP 1 LAST Q_DEPT BU9
J 1
(-3763 49);
DISPLAY 1.957447 (-3763 49);
PAINT GREEN (-3763 49);
FORCEPROP 2 LAST CUSTOM_TXT_CDS <XR_PAGE_TITLE>
J 0
(-7890 5250);
DISPLAY 0.638298 (-7890 5250);
PAINT PINK (-7890 5250);
DISPLAY INVISIBLE (-7890 5250);
FORCEPROP 2 LAST PAGE_BORDER TRUE
J 0
(-7890 5250);
DISPLAY 0.638298 (-7890 5250);
PAINT PINK (-7890 5250);
DISPLAY INVISIBLE (-7890 5250);
FORCEPROP 2 LAST CDS_LIB pure_quanta
J 0
(0 0);
DISPLAY INVISIBLE (0 0);
FORCEPROP 1 LAST CDS_LMAN_SYM_OUTLINE -9475,6775,100,-125
J 0
(0 0);
DISPLAY 0.468085 (0 0);
PAINT GREEN (0 0);
DISPLAY INVISIBLE (0 0);
FORCEPROP 1 LAST COMMENT_BODY TRUE
J 0
(12 -13);
DISPLAY 0.978723 (12 -13);
PAINT GREEN (12 -13);
DISPLAY INVISIBLE (12 -13);
FORCEPROP 2 LAST CDS_XR_PAGE_TITLE CR-127 : @T6G_MB_LIB.T6G(SCH_1):PAGE127
J 0
(-7890 5250);
DISPLAY 0.638298 (-7890 5250);
PAINT PINK (-7890 5250);
DISPLAY INVISIBLE (-7890 5250);
FORCEPROP 0 LAST CDS_CON_LAST_MODIFIED Wed Mar 09 18:12:39 2022
J 0
(-1885 15);
DISPLAY INVISIBLE (-1885 15);
QUIT
